# S9S_MB_2U (Grand Teton) — schematic parts with pin connectivity, parts 3506–3649 of 6093; source: Cadence DE-HDL packaged netlist (pstxprt.dat, pstxnet.dat, pstchip.dat)

R417  Q_RES  0 5% CHIP  pkg 0402LF  page 153 : 1 = OCP_SFF_ISO_BIF1_EN ; 2 = OCP_SFF_BIF1_R_N
R418  Q_RES  0 5% CHIP  pkg 0402LF  page 153 : 1 = OCP_SFF_ISO_BIF2_EN ; 2 = OCP_SFF_BIF2_R_N
R419  Q_RES  33.2 1% CHIP  pkg 0402LF  page 155 : 1 = RST_OCP_V3_1_BUF_N ; 2 = RST_PERST0_OCP_SFF_N
R420  Q_RES  1K 1% CHIP  pkg 0402LF  page 153 : 1 = SGPIO_OCP_SFF_LD_N ; 2 = P3V3_OCP_SFF
R421  Q_RES  10K 1% CHIP  pkg 0402LF  page 153 : 1 = SGPIO_OCP_SFF_DATAIN ; 2 = P3V3_OCP_SFF
R422  Q_RES  10K 1% CHIP  pkg 0402LF  page 153 : 1 = SGPIO_OCP_SFF_DATAOUT ; 2 = GND
R423  Q_RES  1K 1% CHIP  pkg 0402LF  page 153 : 1 = SGPIO_OCP_SFF_CLK ; 2 = P3V3_OCP_SFF
R424  Q_RES  33.2 1% CHIP  pkg 0402LF  page 153 : 1 = SMB_OCP_SFF_3V3AUX_BUF_R_SCL ; 2 = SMB_OCP_SFF_3V3AUX_BUF_SCL
R425  Q_RES  200 1% CHIP  pkg 0402LF  page 153 : 1 = SMB_OCP_SFF_3V3AUX_BUF_R_SDA ; 2 = SMB_OCP_SFF_3V3AUX_BUF_SDA
R429  Q_RES  0 5% CHIP  pkg 0402LF  page 153 : 1 = OCP_SFF_MAIN_PWR_EN ; 2 = OCP_SFF_MAIN_PWR_EN_R
R435  Q_RES  33.2 1% CHIP  pkg 0402LF  page 155 : 1 = RST_OCP_V3_1_BUF_N ; 2 = RST_PERST1_OCP_SFF_N
R442  Q_RES  1 1% CHIP  pkg 0603LF  page 210 : 1 = P3V3_AUX_CLK_GEN_VDDXTAL_CK440 ; 2 = P3V3_AUX_CLK_GEN_VDDA25M_CK440
R444  Q_RES  0 5% CHIP  pkg 0402LF  page 153 : 1 = OCP_SFF_USB2_3_DN ; 2 = USB2_3_DN
R445  Q_RES  0 5% CHIP  pkg 0402LF  page 153 : 1 = OCP_SFF_USB2_3_DP ; 2 = USB2_3_DP
R447  Q_RES  1 1% CHIP  pkg 0603LF  page 210 : 1 = P3V3_AUX_CLK_GEN_VDDMXCK_CK440 ; 2 = P3V3_AUX_CLK_GEN_VDDPT_CK440
R448  Q_RES  0 5% EMPTY  pkg 0402LF  page 236 : 1 = SMB_S3M_CPU0_3V3AUX_SCL ; 2 = SMB_S3M_CPU1_3V3AUX_SCL
R453  Q_RES  10K 1% CHIP  pkg 0402LF  page 182 : 1 = P3V3_AUX ; 2 = PU_LAN_WAKE_N
R456  Q_RES  10K 1% CHIP  pkg 0402LF  page 204 : 1 = P3V3_AUX ; 2 = PU_PCH_PMCALERT_N
R474  Q_RES  33.2 1% CHIP  pkg 0402LF  page 183 : 1 = FM_PCHHOT_N ; 2 = FM_PCHHOT_R_N
R477  Q_RES  60.4 1% CHIP  pkg 0402LF  page 179 : 1 = PD_PCH_XCLK_BIASREF ; 2 = GND
R478  Q_RES  4.7K 1% CHIP  pkg 0402LF  page 190 : 1 = P3V3_AUX ; 2 = PCIE_M2_SSD0_PRSNT_N
R480  Q_RES  0 5% CHIP  pkg 0402LF  page 239 : 1 = JTAG_DBP_TMS ; 2 = JTAG_DBP_FB_TMS
R481  Q_RES  0 5% CHIP  pkg 0402LF  page 239 : 1 = JTAG_DBP_TDI ; 2 = JTAG_DBP_FB_TDI
R482  Q_RES  0 5% CHIP  pkg 0402LF  page 239 : 1 = JTAG_DBP_PREQ_N ; 2 = JTAG_DBP_PREQ_R_N
R483  Q_RES  0 5% CHIP  pkg 0402LF  page 239 : 1 = JTAG_BMC_DBP_TDO_R ; 2 = JTAG_BMC_DBP_TDO
R486  Q_RES  0 5% CHIP  pkg 0402LF  page 190 : 1 = M2_SSD0_CLKREQ_EN_N ; 2 = M2_SSD0_CLKREQ_EN_N_BUF
R487  Q_RES  1K 1% CHIP  pkg 0402LF  page 190 : 1 = P3V3_AUX ; 2 = M2_SSD0_CLKREQ_EN_N_BUF
R491  Q_RES  4.7K 1% EMPTY  pkg 0402LF  page 190 : 1 = M2_SSD0_CLKREQ_EN_N ; 2 = GND
R494  Q_RES  1K 1% CHIP  pkg 0402LF  page 182 : 1 = P3V3_AUX ; 2 = IRQ_LVC3_WAKE_N
R495  Q_RES  100 1% CHIP  pkg 0402LF  page 181 : 1 = PCH_PCIEUP_RCOMPP ; 2 = PCH_PCIEUP_RCOMPN
R496  Q_RES  113 1% CHIP  pkg 0402LF  page 180 : 1 = PD_PCH_USB2_COMP ; 2 = GND
R497  Q_RES  200 1% CHIP  pkg 0402LF  page 187 : 1 = PD_RCOMP_1P8_3P3 ; 2 = GND
R498  Q_RES  10K 1% CHIP  pkg 0402LF  page 185 : 1 = P3V3_AUX ; 2 = FM_PCH_PRSNT_N
R499  Q_RES  33.2 1% CHIP  pkg 0402LF  page 185 : 1 = SPI_PCH_CLK ; 2 = SPI_SYS_CLK
R501  Q_RES  33.2 1% CHIP  pkg 0402LF  page 185 : 1 = SPI_PCH_CS0_R_N ; 2 = SPI_SYS_CS0_N
R502  Q_RES  20K 1% CHIP  pkg 0402LF  page 198 : 1 = P3V3_AUX ; 2 = FM_PCH_CONSENT_STRAP_N
R506  Q_RES  0 5% CHIP  pkg 0402LF  page 240 : 1 = IRQ_SMI_ACTIVE_BMC_N ; 2 = IRQ0_A57
R515  Q_RES  10K 1% CHIP  pkg 0402LF  page 127 : 1 = PD_PIROM_CPU0_ADDR0 ; 2 = GND
R519  Q_RES  1 1% CHIP  pkg 0603LF  page 210 : 1 = P3V3_AUX_CLK_GEN_VDD_CK440 ; 2 = P3V3_AUX_CLK_GEN_VDDA100M_CK440
R536  Q_RES  10K 1% EMPTY  pkg 0402LF  page 231 : 1 = P3V3_AUX ; 2 = PCA9548_PCIE3_ADDR2
R537  Q_RES  1K 1% CHIP  pkg 0402LF  page 231 : 1 = PCA9548_PCIE3_ADDR2 ; 2 = GND
R538  Q_RES  10K 1% EMPTY  pkg 0402LF  page 231 : 1 = P3V3_AUX ; 2 = PCA9548_PCIE3_ADDR1
R539  Q_RES  1K 1% CHIP  pkg 0402LF  page 231 : 1 = PCA9548_PCIE3_ADDR1 ; 2 = GND
R540  Q_RES  10K 1% EMPTY  pkg 0402LF  page 231 : 1 = P3V3_AUX ; 2 = PCA9548_PCIE3_ADDR0
R548  Q_RES  49.9 1% CHIP  pkg 0402LF  page 14 : 1 = SVID_ALERT0_CPU0_R_N ; 2 = PVNN_TERM_CPU0
R553  Q_RES  0 5% CHIP  pkg 0402LF  page 209 : 1 = CLK_100M_CK440_PCH_EXTCLK_R_DP ; 2 = CLK_100M_CK440_PCH_EXTCLK_DP
R554  Q_RES  0 5% CHIP  pkg 0402LF  page 209 : 1 = CLK_100M_CK440_PCH_EXTCLK_R_DN ; 2 = CLK_100M_CK440_PCH_EXTCLK_DN
R555  Q_RES  100 1% CHIP  pkg 0402LF  page 14 : 1 = SVID_DIO1_CPU0_R ; 2 = PVNN_TERM_CPU0
R556  Q_RES  49.9 1% CHIP  pkg 0402LF  page 14 : 1 = SVID_ALERT1_CPU0_R_N ; 2 = PVNN_TERM_CPU0
R557  Q_RES  100 1% CHIP  pkg 0402LF  page 45 : 1 = SVID_DIO0_CPU1_R ; 2 = PVNN_TERM_CPU1
R558  Q_RES  49.9 1% CHIP  pkg 0402LF  page 45 : 1 = SVID_ALERT0_CPU1_R_N ; 2 = PVNN_TERM_CPU1
R559  Q_RES  100 1% CHIP  pkg 0402LF  page 45 : 1 = SVID_DIO1_CPU1_R ; 2 = PVNN_TERM_CPU1
R560  Q_RES  49.9 1% CHIP  pkg 0402LF  page 45 : 1 = SVID_ALERT1_CPU1_R_N ; 2 = PVNN_TERM_CPU1
R563  Q_RES  22 1% CHIP  pkg 0402LF  page 209 : 1 = CLK_100M_OCP_SFF_0_R_DP ; 2 = CLK_100M_OCP_SFF_0_DP
R564  Q_RES  22 1% CHIP  pkg 0402LF  page 209 : 1 = CLK_100M_OCP_SFF_0_R_DN ; 2 = CLK_100M_OCP_SFF_0_DN
R565  Q_RES  22 1% CHIP  pkg 0402LF  page 209 : 1 = CLK_100M_OCP_SFF_1_R_DP ; 2 = CLK_100M_OCP_SFF_1_DP
R566  Q_RES  22 1% CHIP  pkg 0402LF  page 209 : 1 = CLK_100M_OCP_SFF_1_R_DN ; 2 = CLK_100M_OCP_SFF_1_DN
R567  Q_RES  4.7K 1% EMPTY  pkg 0402LF  page 206 : 1 = P3V3 ; 2 = PD_DB2000_SMB_SA1
R568  Q_RES  4.7K 1% CHIP  pkg 0402LF  page 206 : 1 = PD_DB2000_SMB_SA1 ; 2 = GND
R569  Q_RES  4.7K 1% EMPTY  pkg 0402LF  page 206 : 1 = P3V3 ; 2 = PD_DB2000_SMB_SA0
R570  Q_RES  4.7K 1% CHIP  pkg 0402LF  page 206 : 1 = PD_DB2000_SMB_SA0 ; 2 = GND
R571  Q_RES  2.2 1% CHIP  pkg 0603LF  page 206 : 1 = P3V3_DB2000_FB_VDD ; 2 = P3V3_DB2000_VDDR
R572  Q_RES  2.2 1% CHIP  pkg 0603LF  page 206 : 1 = P3V3_DB2000_FB_VDD ; 2 = P3V3_DB2000_VDDA
R573  Q_RES  4.7K 1% EMPTY  pkg 0402LF  page 206 : 1 = P3V3 ; 2 = FM_DB2000_VSBEN
R574  Q_RES  4.7K 1% CHIP  pkg 0402LF  page 206 : 1 = FM_DB2000_VSBEN ; 2 = GND
R575  Q_RES  49.9 1% CHIP  pkg 0402LF  page 206 : 1 = FM_PLD_CLKS_DEV_EN ; 2 = FM_DB2000_DEV_EN
R576  Q_RES  49.9 1% CHIP  pkg 0402LF  page 206 : 1 = FM_DB2000_OE_N ; 2 = FM_DB2000_1_OE_N
R577  Q_RES  33.2 1% CHIP  pkg 0402LF  page 241 : 1 = SMB_HOST_3V3AUX_SCL_R4 ; 2 = SMB_HOST_3V3AUX_SCL_R
R578  Q_RES  33.2 1% CHIP  pkg 0402LF  page 241 : 1 = SMB_HOST_3V3AUX_SDA_R4 ; 2 = SMB_HOST_3V3AUX_SDA_R
R579  Q_RES  33.2 1% CHIP  pkg 0402LF  page 241 : 1 = SMB_HOST_3V3AUX_SCL_R5 ; 2 = SMB_HOST_BMC_3V3AUX_SCL
R580  Q_RES  33.2 1% CHIP  pkg 0402LF  page 241 : 1 = SMB_HOST_3V3AUX_SDA_R5 ; 2 = SMB_HOST_BMC_3V3AUX_SDA
R581  Q_RES  33.2 1% CHIP  pkg 0402LF  page 241 : 1 = SMB_SML0_3V3AUX_SCL ; 2 = SMB_SML0_3V3AUX_PCH_SCL
R582  Q_RES  33.2 1% CHIP  pkg 0402LF  page 241 : 1 = SMB_SML0_3V3AUX_SDA ; 2 = SMB_SML0_3V3AUX_PCH_SDA
R587  Q_RES  1K 1% CHIP  pkg 0402LF  page 231 : 1 = PCA9548_PCIE3_ADDR0 ; 2 = GND
R588  Q_RES  33.2 1% CHIP  pkg 0402LF  page 231 : 1 = SMB_PCIE0_3V3AUX_SCL ; 2 = SMB_PCIE0_3V3AUX_SCL_R
R589  Q_RES  33.2 1% CHIP  pkg 0402LF  page 231 : 1 = SMB_PCIE0_3V3AUX_SDA ; 2 = SMB_PCIE0_3V3AUX_SDA_R
R592  Q_RES  2.2K 5% EMPTY  pkg 0402LF  page 241 : 1 = SMB_FAN_3V3AUX_SCL ; 2 = P3V3_AUX
R593  Q_RES  0 5% CHIP  pkg 0402LF  page 241 : 1 = I3C_SPD_DDRABCD_CPU0_BMC_R_SCL ; 2 = I3C_SPD_DDRABCD_CPU0_BMC_SCL
R594  Q_RES  0 5% CHIP  pkg 0402LF  page 241 : 1 = I3C_SPD_DDRABCD_CPU0_BMC_R_SDA ; 2 = I3C_SPD_DDRABCD_CPU0_BMC_SDA
R595  Q_RES  0 5% CHIP  pkg 0402LF  page 241 : 1 = I3C_SPD_DDREFGH_CPU0_BMC_R_SCL ; 2 = I3C_SPD_DDREFGH_CPU0_BMC_SCL
R596  Q_RES  0 5% CHIP  pkg 0402LF  page 241 : 1 = I3C_SPD_DDREFGH_CPU0_BMC_R_SDA ; 2 = I3C_SPD_DDREFGH_CPU0_BMC_SDA
R597  Q_RES  0 5% CHIP  pkg 0402LF  page 241 : 1 = I3C_SPD_DDRABCD_CPU1_BMC_R_SCL ; 2 = I3C_SPD_DDRABCD_CPU1_BMC_SCL
R598  Q_RES  0 5% CHIP  pkg 0402LF  page 241 : 1 = I3C_SPD_DDRABCD_CPU1_BMC_R_SDA ; 2 = I3C_SPD_DDRABCD_CPU1_BMC_SDA
R599  Q_RES  0 5% CHIP  pkg 0402LF  page 241 : 1 = I3C_SPD_DDREFGH_CPU1_BMC_R_SCL ; 2 = I3C_SPD_DDREFGH_CPU1_BMC_SCL
R600  Q_RES  0 5% CHIP  pkg 0402LF  page 241 : 1 = I3C_SPD_DDREFGH_CPU1_BMC_R_SDA ; 2 = I3C_SPD_DDREFGH_CPU1_BMC_SDA
R601  Q_RES  2.2K 5% EMPTY  pkg 0402LF  page 241 : 1 = SMB_FAN_3V3AUX_SDA ; 2 = P3V3_AUX
R607  Q_RES  1K 1% EMPTY  pkg 0402LF  page 199 : 1 = P3V3_AUX ; 2 = FM_ESPI_FLASH_MODE
R608  Q_RES  10K 1% CHIP  pkg 0402LF  page 199 : 1 = FM_ESPI_FLASH_MODE ; 2 = GND
R609  Q_RES  1K 1% EMPTY  pkg 0402LF  page 199 : 1 = P3V3_AUX ; 2 = FM_ESPI_CS_SWIZZLE
R610  Q_RES  10K 1% CHIP  pkg 0402LF  page 199 : 1 = FM_ESPI_CS_SWIZZLE ; 2 = GND
R611  Q_RES  1K 1% CHIP  pkg 0402LF  page 199 : 1 = P3V3_AUX ; 2 = FM_PCH_EXTERNALCLKMODE
R612  Q_RES  10K 1% EMPTY  pkg 0402LF  page 199 : 1 = FM_PCH_EXTERNALCLKMODE ; 2 = GND
R613  Q_RES  10K 1% CHIP  pkg 0402LF  page 199 : 1 = P3V3_AUX ; 2 = FM_JTAG_ODT_DISABLE
R614  Q_RES  1K 1% EMPTY  pkg 0402LF  page 199 : 1 = FM_JTAG_ODT_DISABLE ; 2 = GND
R615  Q_RES  1K 1% CHIP  pkg 0402LF  page 199 : 1 = P3V3_AUX ; 2 = FM_PCH_VISA_DEFAULT
R617  Q_RES  1K 1% EMPTY  pkg 0402LF  page 199 : 1 = P3V3_AUX ; 2 = FM_PCH_IO_EXPANDER
R618  Q_RES  10K 1% CHIP  pkg 0402LF  page 199 : 1 = FM_PCH_IO_EXPANDER ; 2 = GND
R619  Q_RES  10K 1% CHIP  pkg 0402LF  page 199 : 1 = P3V3_AUX ; 2 = FM_LT_KEY_DOWNGRADE_N
R621  Q_RES  1K 1% EMPTY  pkg 0402LF  page 199 : 1 = P3V3_AUX ; 2 = FM_PCH_SKIP_RTC_CLOCK
R622  Q_RES  1K 1% CHIP  pkg 0402LF  page 199 : 1 = FM_PCH_SKIP_RTC_CLOCK ; 2 = GND
R623  Q_RES  1K 1% EMPTY  pkg 0402LF  page 199 : 1 = P3V3_AUX ; 2 = FM_PCH_XTALSEL
R624  Q_RES  10K 1% CHIP  pkg 0402LF  page 199 : 1 = FM_PCH_XTALSEL ; 2 = GND
R625  Q_RES  1K 1% EMPTY  pkg 0402LF  page 127 : 1 = P3V3_AUX ; 2 = PD_PIROM_CPU1_ADDR2
R626  Q_RES  10K 1% CHIP  pkg 0402LF  page 127 : 1 = PD_PIROM_CPU1_ADDR2 ; 2 = GND
R627  Q_RES  1K 1% EMPTY  pkg 0402LF  page 127 : 1 = P3V3_AUX ; 2 = PD_PIROM_CPU1_ADDR1
R628  Q_RES  10K 1% CHIP  pkg 0402LF  page 127 : 1 = PD_PIROM_CPU1_ADDR1 ; 2 = GND
R629  Q_RES  1K 1% CHIP  pkg 0402LF  page 127 : 1 = P3V3_AUX ; 2 = PU_PIROM_CPU1_ADDR0
R630  Q_RES  10K 1% EMPTY  pkg 0402LF  page 127 : 1 = PU_PIROM_CPU1_ADDR0 ; 2 = GND
R635  Q_RES  10K 1% CHIP  pkg 0402LF  page 183 : 1 = PU_OC3_USB_N ; 2 = P3V3_AUX
R650  Q_RES  1K 1% CHIP  pkg 0402LF  page 127 : 1 = P3V3_AUX ; 2 = PU_PIROM_CPU0_SM_WP
R651  Q_RES  2.2K 5% CHIP  pkg 0402LF  page 231 : 1 = P3V3_AUX ; 2 = SMB_FRU_3V3AUX_SCL
R652  Q_RES  2.2K 5% CHIP  pkg 0402LF  page 231 : 1 = P3V3_AUX ; 2 = SMB_FRU_3V3AUX_SDA
R661  Q_RES  1K 1% CHIP  pkg 0402LF  page 230 : 1 = PD_I3C_SPD_DDR_CPU1_OE_N ; 2 = GND
R662  Q_RES  499 1% CHIP  pkg 0402LF  page 230 : 1 = PVNN_TERM_CPU1 ; 2 = I3C_SPD_DDRABCD_CPU1_SCL
R663  Q_RES  499 1% CHIP  pkg 0402LF  page 230 : 1 = PVNN_TERM_CPU1 ; 2 = I3C_SPD_DDRABCD_CPU1_SDA
R664  Q_RES  499 1% CHIP  pkg 0402LF  page 230 : 1 = PVNN_TERM_CPU1 ; 2 = I3C_SPD_DDREFGH_CPU1_SCL
R665  Q_RES  0 5% EMPTY  pkg 0402LF  page 230 : 1 = I3C_SPD_DDRABCD_CPU1_R_SCL ; 2 = I3C_SPD_DDRABCD_CPU1_LVC1_R_SCL
R666  Q_RES  0 5% EMPTY  pkg 0402LF  page 230 : 1 = I3C_SPD_DDRABCD_CPU1_R_SDA ; 2 = I3C_SPD_DDRABCD_CPU1_LVC1_R_SDA
R667  Q_RES  0 5% EMPTY  pkg 0402LF  page 230 : 1 = I3C_SPD_DDREFGH_CPU1_R_SCL ; 2 = I3C_SPD_DDREFGH_CPU1_LVC1_R_SCL
R668  Q_RES  0 5% EMPTY  pkg 0402LF  page 230 : 1 = I3C_SPD_DDREFGH_CPU1_R_SDA ; 2 = I3C_SPD_DDREFGH_CPU1_LVC1_R_SDA
R669  Q_RES  499 1% CHIP  pkg 0402LF  page 230 : 1 = PVNN_TERM_CPU1 ; 2 = I3C_SPD_DDREFGH_CPU1_SDA
R670  Q_RES  0 5% CHIP  pkg 0402LF  page 230 : 1 = I3C_SPD_DDRABCD_CPU1_SCL ; 2 = I3C_SPD_DDRABCD_CPU1_R_SCL
R671  Q_RES  33.2 1% CHIP  pkg 0402LF  page 230 : 1 = I3C_SPD_DDRABCD_CPU1_SDA ; 2 = I3C_SPD_DDRABCD_CPU1_R_SDA
R672  Q_RES  0 5% CHIP  pkg 0402LF  page 230 : 1 = I3C_SPD_DDREFGH_CPU1_SCL ; 2 = I3C_SPD_DDREFGH_CPU1_R_SCL
R673  Q_RES  33.2 1% CHIP  pkg 0402LF  page 230 : 1 = I3C_SPD_DDREFGH_CPU1_SDA ; 2 = I3C_SPD_DDREFGH_CPU1_R_SDA
R674  Q_RES  0 5% CHIP  pkg 0402LF  page 230 : 1 = I3C_SPD_DDRABCD_CPU1_LVC1_R_SCL ; 2 = I3C_SPD_DDRABCD_CPU1_LVC1_SCL
R675  Q_RES  33.2 1% CHIP  pkg 0402LF  page 230 : 1 = I3C_SPD_DDRABCD_CPU1_LVC1_R_SDA ; 2 = I3C_SPD_DDRABCD_CPU1_LVC1_SDA
R676  Q_RES  0 5% CHIP  pkg 0402LF  page 230 : 1 = I3C_SPD_DDREFGH_CPU1_LVC1_R_SCL ; 2 = I3C_SPD_DDREFGH_CPU1_LVC1_SCL
R677  Q_RES  33.2 1% CHIP  pkg 0402LF  page 230 : 1 = I3C_SPD_DDREFGH_CPU1_LVC1_R_SDA ; 2 = I3C_SPD_DDREFGH_CPU1_LVC1_SDA
R678  Q_RES  1K 1% CHIP  pkg 0402LF  page 229 : 1 = PD_I3C_SPD_DDR_CPU0_OE_N ; 2 = GND
R679  Q_RES  499 1% CHIP  pkg 0402LF  page 229 : 1 = PVNN_TERM_CPU0 ; 2 = I3C_SPD_DDRABCD_CPU0_SCL
R680  Q_RES  499 1% CHIP  pkg 0402LF  page 229 : 1 = PVNN_TERM_CPU0 ; 2 = I3C_SPD_DDRABCD_CPU0_SDA
R681  Q_RES  499 1% CHIP  pkg 0402LF  page 229 : 1 = PVNN_TERM_CPU0 ; 2 = I3C_SPD_DDREFGH_CPU0_SCL
R682  Q_RES  0 5% EMPTY  pkg 0402LF  page 229 : 1 = I3C_SPD_DDRABCD_CPU0_R_SCL ; 2 = I3C_SPD_DDRABCD_CPU0_LVC1_R_SCL
R683  Q_RES  0 5% EMPTY  pkg 0402LF  page 229 : 1 = I3C_SPD_DDRABCD_CPU0_R_SDA ; 2 = I3C_SPD_DDRABCD_CPU0_LVC1_R_SDA
R684  Q_RES  0 5% EMPTY  pkg 0402LF  page 229 : 1 = I3C_SPD_DDREFGH_CPU0_R_SCL ; 2 = I3C_SPD_DDREFGH_CPU0_LVC1_R_SCL
R685  Q_RES  0 5% EMPTY  pkg 0402LF  page 229 : 1 = I3C_SPD_DDREFGH_CPU0_R_SDA ; 2 = I3C_SPD_DDREFGH_CPU0_LVC1_R_SDA
R686  Q_RES  499 1% CHIP  pkg 0402LF  page 229 : 1 = PVNN_TERM_CPU0 ; 2 = I3C_SPD_DDREFGH_CPU0_SDA
R687  Q_RES  0 5% CHIP  pkg 0402LF  page 229 : 1 = I3C_SPD_DDRABCD_CPU0_SCL ; 2 = I3C_SPD_DDRABCD_CPU0_R_SCL
R688  Q_RES  33.2 1% CHIP  pkg 0402LF  page 229 : 1 = I3C_SPD_DDRABCD_CPU0_SDA ; 2 = I3C_SPD_DDRABCD_CPU0_R_SDA
R689  Q_RES  0 5% CHIP  pkg 0402LF  page 229 : 1 = I3C_SPD_DDREFGH_CPU0_SCL ; 2 = I3C_SPD_DDREFGH_CPU0_R_SCL
R690  Q_RES  33.2 1% CHIP  pkg 0402LF  page 229 : 1 = I3C_SPD_DDREFGH_CPU0_SDA ; 2 = I3C_SPD_DDREFGH_CPU0_R_SDA
R691  Q_RES  0 5% CHIP  pkg 0402LF  page 229 : 1 = I3C_SPD_DDRABCD_CPU0_LVC1_R_SCL ; 2 = I3C_SPD_DDRABCD_CPU0_LVC1_SCL
R692  Q_RES  33.2 1% CHIP  pkg 0402LF  page 229 : 1 = I3C_SPD_DDRABCD_CPU0_LVC1_R_SDA ; 2 = I3C_SPD_DDRABCD_CPU0_LVC1_SDA
